(kicad_pcb
	(version 20260206)
	(generator "pcbnew")
	(generator_version "10.0")
	(general
		(thickness 1.6)
		(legacy_teardrops no)
	)
	(paper "A4")
	(title_block
		(title "12092022_DA0F0TMDCD0_F0T_Management_Board_D_brd_V3_OCP.brd")
		(comment 1 "Grand Teton / footprints 110-115 of 1440")
	)
	(layers
		(0 "F.Cu" signal "TOP")
		(4 "In1.Cu" signal "GND")
		(6 "In2.Cu" signal "IN1")
		(8 "In3.Cu" signal "GND1")
		(10 "In4.Cu" signal "IN2")
		(12 "In5.Cu" signal "VCC")
		(14 "In6.Cu" signal "VCC1")
		(16 "In7.Cu" signal "IN3")
		(18 "In8.Cu" signal "GND2")
		(20 "In9.Cu" signal "IN4")
		(22 "In10.Cu" signal "GND3")
		(2 "B.Cu" signal "BOTTOM")
		(9 "F.Adhes" user "F.Adhesive")
		(11 "B.Adhes" user "B.Adhesive")
		(13 "F.Paste" user "Package Geometry/Pastemask Top")
		(15 "B.Paste" user "Package Geometry/Pastemask Bottom")
		(5 "F.SilkS" user "Ref Des/Silkscreen Top")
		(7 "B.SilkS" user "Ref Des/Silkscreen Bottom")
		(1 "F.Mask" user "Board Geometry/Soldermask Top")
		(3 "B.Mask" user "Board Geometry/Soldermask Bottom")
		(17 "Dwgs.User" user "User.Drawings")
		(19 "Cmts.User" user "User.Comments")
		(21 "Eco1.User" user "User.Eco1")
		(23 "Eco2.User" user "User.Eco2")
		(25 "Edge.Cuts" user "Board Geometry/Outline")
		(27 "Margin" user)
		(31 "F.CrtYd" user "Package Geometry/Place Bound Top")
		(29 "B.CrtYd" user "Package Geometry/Place Bound Bottom")
		(35 "F.Fab" user "Ref Des/Assembly Top")
		(33 "B.Fab" user "Ref Des/Assembly Bottom")
	)
	(footprint ""
		(layer "F.Cu")
		(at 77.281786 -27.738832 90)
		(property "Reference" "D1"
			(at -1.780032 7.911084 90)
			(unlocked yes)
			(layer "F.SilkS")
			(effects
				(font
					(size 0.7874 0.5842)
					(thickness 0.1524)
				)
				(justify left)
			)
		)
		(property "Value" ""
			(at 0 0 90)
			(layer "F.Fab")
			(effects
				(font
					(size 1.27 1.27)
				)
			)
		)
		(duplicate_pad_numbers_are_jumpers no)
		(fp_line
			(start 1.778 -0.5588)
			(end 1.3208 -0.5588)
			(stroke
				(width 0.1524)
				(type default)
			)
			(layer "F.SilkS")
		)
		(fp_line
			(start 1.778 -0.5588)
			(end 1.778 0.5588)
			(stroke
				(width 0.1524)
				(type default)
			)
			(layer "F.SilkS")
		)
		(fp_line
			(start 1.4732 -0.5588)
			(end 1.4732 0.5588)
			(stroke
				(width 0.1524)
				(type default)
			)
			(layer "F.SilkS")
		)
		(fp_line
			(start 1.3208 -0.5588)
			(end 1.3208 0.5588)
			(stroke
				(width 0.1524)
				(type default)
			)
			(layer "F.SilkS")
		)
		(fp_line
			(start -1.3208 -0.5588)
			(end 1.3208 -0.5588)
			(stroke
				(width 0.1524)
				(type default)
			)
			(layer "F.SilkS")
		)
		(fp_line
			(start 1.778 0.5588)
			(end 1.3208 0.5588)
			(stroke
				(width 0.1524)
				(type default)
			)
			(layer "F.SilkS")
		)
		(fp_line
			(start 1.6256 0.5588)
			(end 1.6256 -0.5588)
			(stroke
				(width 0.1524)
				(type default)
			)
			(layer "F.SilkS")
		)
		(fp_line
			(start 1.3208 0.5588)
			(end -1.3208 0.5588)
			(stroke
				(width 0.1524)
				(type default)
			)
			(layer "F.SilkS")
		)
		(fp_line
			(start -1.3208 0.5588)
			(end -1.3208 -0.5588)
			(stroke
				(width 0.1524)
				(type default)
			)
			(layer "F.SilkS")
		)
		(fp_line
			(start 1.236726 -0.508)
			(end 1.1684 -0.508)
			(stroke
				(width 0.1)
				(type default)
			)
			(layer "F.Fab")
		)
		(fp_line
			(start 1.1684 -0.508)
			(end -1.1684 -0.508)
			(stroke
				(width 0.1)
				(type default)
			)
			(layer "F.Fab")
		)
		(fp_line
			(start -1.1684 -0.508)
			(end -1.235964 -0.508)
			(stroke
				(width 0.1)
				(type default)
			)
			(layer "F.Fab")
		)
		(fp_line
			(start -1.235964 -0.508)
			(end -1.235964 0.508)
			(stroke
				(width 0.1)
				(type default)
			)
			(layer "F.Fab")
		)
		(fp_line
			(start 1.236726 0.508)
			(end 1.236726 -0.508)
			(stroke
				(width 0.1)
				(type default)
			)
			(layer "F.Fab")
		)
		(fp_line
			(start 1.1684 0.508)
			(end 1.236726 0.508)
			(stroke
				(width 0.1)
				(type default)
			)
			(layer "F.Fab")
		)
		(fp_line
			(start -1.1684 0.508)
			(end 1.1684 0.508)
			(stroke
				(width 0.1)
				(type default)
			)
			(layer "F.Fab")
		)
		(fp_line
			(start -1.235964 0.508)
			(end -1.1684 0.508)
			(stroke
				(width 0.1)
				(type default)
			)
			(layer "F.Fab")
		)
		(fp_text user "+"
			(at -2.669032 -0.186436 90)
			(unlocked yes)
			(layer "F.SilkS")
			(effects
				(font
					(size 1.905 1.4224)
					(thickness 0.1524)
				)
				(justify left)
			)
		)
		(fp_text user "-"
			(at 0.675386 0.592582 90)
			(unlocked yes)
			(layer "F.SilkS")
			(effects
				(font
					(size 1.905 1.4224)
					(thickness 0.1524)
				)
				(justify left)
			)
		)
		(fp_text user "-"
			(at 1.524 -0.24765 90)
			(unlocked yes)
			(layer "F.Fab")
			(effects
				(font
					(size 1.905 1.4224)
					(thickness 0.1524)
				)
				(justify left)
			)
		)
		(fp_text user "+"
			(at -2.5654 -0.24765 90)
			(unlocked yes)
			(layer "F.Fab")
			(effects
				(font
					(size 1.905 1.4224)
					(thickness 0.1524)
				)
				(justify left)
			)
		)
		(pad "A" smd rect
			(at -0.750062 0 90)
			(size 0.8128 0.8128)
			(layers "F.Cu" "F.Mask" "F.Paste")
			(net "LED_POSTCODE_1_R")
		)
		(pad "C" smd rect
			(at 0.750062 0 90)
			(size 0.8128 0.8128)
			(layers "F.Cu" "F.Mask" "F.Paste")
			(net "GND")
		)
	)
	(footprint ""
		(layer "F.Cu")
		(at 52.9082 -106.5784 180)
		(property "Reference" "R862"
			(at 0 0 180)
			(layer "F.SilkS")
			(hide yes)
			(effects
				(font
					(size 1.27 1.27)
				)
			)
		)
		(property "Value" ""
			(at 0 0 180)
			(layer "F.Fab")
			(effects
				(font
					(size 1.27 1.27)
				)
			)
		)
		(duplicate_pad_numbers_are_jumpers no)
		(fp_line
			(start 0.7874 0.4064)
			(end -0.7874 0.4064)
			(stroke
				(width 0.1524)
				(type default)
			)
			(layer "F.SilkS")
		)
		(fp_line
			(start 0.7874 -0.4064)
			(end 0.7874 0.4064)
			(stroke
				(width 0.1524)
				(type default)
			)
			(layer "F.SilkS")
		)
		(fp_line
			(start -0.7874 0.4064)
			(end -0.7874 -0.4064)
			(stroke
				(width 0.1524)
				(type default)
			)
			(layer "F.SilkS")
		)
		(fp_line
			(start -0.7874 -0.4064)
			(end 0.7874 -0.4064)
			(stroke
				(width 0.1524)
				(type default)
			)
			(layer "F.SilkS")
		)
		(fp_line
			(start 0.67945 0.3048)
			(end 0.120396 0.3048)
			(stroke
				(width 0.1)
				(type default)
			)
			(layer "F.Fab")
		)
		(fp_line
			(start 0.67945 -0.3048)
			(end 0.67945 0.3048)
			(stroke
				(width 0.1)
				(type default)
			)
			(layer "F.Fab")
		)
		(fp_line
			(start 0.12065 -0.2794)
			(end 0.12065 -0.3048)
			(stroke
				(width 0.1)
				(type default)
			)
			(layer "F.Fab")
		)
		(fp_line
			(start 0.12065 -0.3048)
			(end 0.67945 -0.3048)
			(stroke
				(width 0.1)
				(type default)
			)
			(layer "F.Fab")
		)
		(fp_line
			(start 0.120396 0.3048)
			(end 0.120396 0.2794)
			(stroke
				(width 0.1)
				(type default)
			)
			(layer "F.Fab")
		)
		(fp_line
			(start 0.120396 0.2794)
			(end -0.12065 0.2794)
			(stroke
				(width 0.1)
				(type default)
			)
			(layer "F.Fab")
		)
		(fp_line
			(start -0.12065 0.3048)
			(end -0.67945 0.3048)
			(stroke
				(width 0.1)
				(type default)
			)
			(layer "F.Fab")
		)
		(fp_line
			(start -0.12065 0.2794)
			(end -0.12065 0.3048)
			(stroke
				(width 0.1)
				(type default)
			)
			(layer "F.Fab")
		)
		(fp_line
			(start -0.12065 -0.2794)
			(end 0.12065 -0.2794)
			(stroke
				(width 0.1)
				(type default)
			)
			(layer "F.Fab")
		)
		(fp_line
			(start -0.12065 -0.305054)
			(end -0.12065 -0.2794)
			(stroke
				(width 0.1)
				(type default)
			)
			(layer "F.Fab")
		)
		(fp_line
			(start -0.67945 0.3048)
			(end -0.67945 -0.305054)
			(stroke
				(width 0.1)
				(type default)
			)
			(layer "F.Fab")
		)
		(fp_line
			(start -0.67945 -0.305054)
			(end -0.12065 -0.305054)
			(stroke
				(width 0.1)
				(type default)
			)
			(layer "F.Fab")
		)
		(pad "1" smd circle
			(at -0.40005 0 180)
			(size 0 0)
			(layers "F.Cu" "F.Mask" "F.Paste")
			(net "SPI_SYS_WP_R_IO2")
		)
		(pad "2" smd circle
			(at 0.40005 0 180)
			(size 0 0)
			(layers "F.Cu" "F.Mask" "F.Paste")
			(net "SPI_SYS_MUX_WP_IO2")
		)
	)
	(footprint ""
		(layer "F.Cu")
		(at 45.212 -26.8732 90)
		(property "Reference" "R395"
			(at 0 0 90)
			(layer "F.SilkS")
			(hide yes)
			(effects
				(font
					(size 1.27 1.27)
				)
			)
		)
		(property "Value" ""
			(at 0 0 90)
			(layer "F.Fab")
			(effects
				(font
					(size 1.27 1.27)
				)
			)
		)
		(duplicate_pad_numbers_are_jumpers no)
		(fp_line
			(start 0.7874 -0.4064)
			(end 0.7874 0.4064)
			(stroke
				(width 0.1524)
				(type default)
			)
			(layer "F.SilkS")
		)
		(fp_line
			(start -0.7874 -0.4064)
			(end 0.7874 -0.4064)
			(stroke
				(width 0.1524)
				(type default)
			)
			(layer "F.SilkS")
		)
		(fp_line
			(start 0.7874 0.4064)
			(end -0.7874 0.4064)
			(stroke
				(width 0.1524)
				(type default)
			)
			(layer "F.SilkS")
		)
		(fp_line
			(start -0.7874 0.4064)
			(end -0.7874 -0.4064)
			(stroke
				(width 0.1524)
				(type default)
			)
			(layer "F.SilkS")
		)
		(fp_line
			(start -0.12065 -0.305054)
			(end -0.12065 -0.2794)
			(stroke
				(width 0.1)
				(type default)
			)
			(layer "F.Fab")
		)
		(fp_line
			(start -0.67945 -0.305054)
			(end -0.12065 -0.305054)
			(stroke
				(width 0.1)
				(type default)
			)
			(layer "F.Fab")
		)
		(fp_line
			(start 0.67945 -0.3048)
			(end 0.67945 0.3048)
			(stroke
				(width 0.1)
				(type default)
			)
			(layer "F.Fab")
		)
		(fp_line
			(start 0.12065 -0.3048)
			(end 0.67945 -0.3048)
			(stroke
				(width 0.1)
				(type default)
			)
			(layer "F.Fab")
		)
		(fp_line
			(start 0.12065 -0.2794)
			(end 0.12065 -0.3048)
			(stroke
				(width 0.1)
				(type default)
			)
			(layer "F.Fab")
		)
		(fp_line
			(start -0.12065 -0.2794)
			(end 0.12065 -0.2794)
			(stroke
				(width 0.1)
				(type default)
			)
			(layer "F.Fab")
		)
		(fp_line
			(start 0.120396 0.2794)
			(end -0.12065 0.2794)
			(stroke
				(width 0.1)
				(type default)
			)
			(layer "F.Fab")
		)
		(fp_line
			(start -0.12065 0.2794)
			(end -0.12065 0.3048)
			(stroke
				(width 0.1)
				(type default)
			)
			(layer "F.Fab")
		)
		(fp_line
			(start 0.67945 0.3048)
			(end 0.120396 0.3048)
			(stroke
				(width 0.1)
				(type default)
			)
			(layer "F.Fab")
		)
		(fp_line
			(start 0.120396 0.3048)
			(end 0.120396 0.2794)
			(stroke
				(width 0.1)
				(type default)
			)
			(layer "F.Fab")
		)
		(fp_line
			(start -0.12065 0.3048)
			(end -0.67945 0.3048)
			(stroke
				(width 0.1)
				(type default)
			)
			(layer "F.Fab")
		)
		(fp_line
			(start -0.67945 0.3048)
			(end -0.67945 -0.305054)
			(stroke
				(width 0.1)
				(type default)
			)
			(layer "F.Fab")
		)
		(pad "1" smd circle
			(at -0.40005 0 90)
			(size 0 0)
			(layers "F.Cu" "F.Mask" "F.Paste")
			(net "PWRGD_P1V0_AUX_DELAY_R")
		)
		(pad "2" smd circle
			(at 0.40005 0 90)
			(size 0 0)
			(layers "F.Cu" "F.Mask" "F.Paste")
			(net "PWRGD_P1V0_AUX_DELAY")
		)
	)
	(footprint ""
		(layer "F.Cu")
		(at 45.5676 -69.2912)
		(property "Reference" "R805"
			(at 0 0 0)
			(layer "F.SilkS")
			(hide yes)
			(effects
				(font
					(size 1.27 1.27)
				)
			)
		)
		(property "Value" ""
			(at 0 0 0)
			(layer "F.Fab")
			(effects
				(font
					(size 1.27 1.27)
				)
			)
		)
		(duplicate_pad_numbers_are_jumpers no)
		(fp_line
			(start -0.7874 -0.4064)
			(end 0.7874 -0.4064)
			(stroke
				(width 0.1524)
				(type default)
			)
			(layer "F.SilkS")
		)
		(fp_line
			(start -0.7874 0.4064)
			(end -0.7874 -0.4064)
			(stroke
				(width 0.1524)
				(type default)
			)
			(layer "F.SilkS")
		)
		(fp_line
			(start 0.7874 -0.4064)
			(end 0.7874 0.4064)
			(stroke
				(width 0.1524)
				(type default)
			)
			(layer "F.SilkS")
		)
		(fp_line
			(start 0.7874 0.4064)
			(end -0.7874 0.4064)
			(stroke
				(width 0.1524)
				(type default)
			)
			(layer "F.SilkS")
		)
		(fp_line
			(start -0.67945 -0.305054)
			(end -0.12065 -0.305054)
			(stroke
				(width 0.1)
				(type default)
			)
			(layer "F.Fab")
		)
		(fp_line
			(start -0.67945 0.3048)
			(end -0.67945 -0.305054)
			(stroke
				(width 0.1)
				(type default)
			)
			(layer "F.Fab")
		)
		(fp_line
			(start -0.12065 -0.305054)
			(end -0.12065 -0.2794)
			(stroke
				(width 0.1)
				(type default)
			)
			(layer "F.Fab")
		)
		(fp_line
			(start -0.12065 -0.2794)
			(end 0.12065 -0.2794)
			(stroke
				(width 0.1)
				(type default)
			)
			(layer "F.Fab")
		)
		(fp_line
			(start -0.12065 0.2794)
			(end -0.12065 0.3048)
			(stroke
				(width 0.1)
				(type default)
			)
			(layer "F.Fab")
		)
		(fp_line
			(start -0.12065 0.3048)
			(end -0.67945 0.3048)
			(stroke
				(width 0.1)
				(type default)
			)
			(layer "F.Fab")
		)
		(fp_line
			(start 0.120396 0.2794)
			(end -0.12065 0.2794)
			(stroke
				(width 0.1)
				(type default)
			)
			(layer "F.Fab")
		)
		(fp_line
			(start 0.120396 0.3048)
			(end 0.120396 0.2794)
			(stroke
				(width 0.1)
				(type default)
			)
			(layer "F.Fab")
		)
		(fp_line
			(start 0.12065 -0.3048)
			(end 0.67945 -0.3048)
			(stroke
				(width 0.1)
				(type default)
			)
			(layer "F.Fab")
		)
		(fp_line
			(start 0.12065 -0.2794)
			(end 0.12065 -0.3048)
			(stroke
				(width 0.1)
				(type default)
			)
			(layer "F.Fab")
		)
		(fp_line
			(start 0.67945 -0.3048)
			(end 0.67945 0.3048)
			(stroke
				(width 0.1)
				(type default)
			)
			(layer "F.Fab")
		)
		(fp_line
			(start 0.67945 0.3048)
			(end 0.120396 0.3048)
			(stroke
				(width 0.1)
				(type default)
			)
			(layer "F.Fab")
		)
		(pad "1" smd circle
			(at -0.40005 0)
			(size 0 0)
			(layers "F.Cu" "F.Mask" "F.Paste")
			(net "P3V3_AUX")
		)
		(pad "2" smd circle
			(at 0.40005 0)
			(size 0 0)
			(layers "F.Cu" "F.Mask" "F.Paste")
			(net "BMC_HEARTBEAT_N")
		)
	)
	(footprint ""
		(layer "F.Cu")
		(at 63.373 -11.176)
		(property "Reference" "Q13"
			(at -1.4224 -1.768348 0)
			(unlocked yes)
			(layer "F.SilkS")
			(effects
				(font
					(size 0.7874 0.5842)
					(thickness 0.1524)
				)
				(justify left)
			)
		)
		(property "Value" ""
			(at 0 0 0)
			(layer "F.Fab")
			(effects
				(font
					(size 1.27 1.27)
				)
			)
		)
		(duplicate_pad_numbers_are_jumpers no)
		(fp_line
			(start -1.332738 -1.100074)
			(end -0.4826 -1.100074)
			(stroke
				(width 0.1524)
				(type default)
			)
			(layer "F.SilkS")
		)
		(fp_line
			(start -1.332738 1.100074)
			(end -1.332738 -1.100074)
			(stroke
				(width 0.1524)
				(type default)
			)
			(layer "F.SilkS")
		)
		(fp_line
			(start -0.4826 -1.100074)
			(end 0 -0.541274)
			(stroke
				(width 0.1524)
				(type default)
			)
			(layer "F.SilkS")
		)
		(fp_line
			(start 0 -0.541274)
			(end 0.4826 -1.100074)
			(stroke
				(width 0.1524)
				(type default)
			)
			(layer "F.SilkS")
		)
		(fp_line
			(start 0.4826 -1.100074)
			(end 1.332738 -1.100074)
			(stroke
				(width 0.1524)
				(type default)
			)
			(layer "F.SilkS")
		)
		(fp_line
			(start 1.332738 -1.100074)
			(end 1.332738 1.100074)
			(stroke
				(width 0.1524)
				(type default)
			)
			(layer "F.SilkS")
		)
		(fp_line
			(start 1.332738 1.100074)
			(end -1.332738 1.100074)
			(stroke
				(width 0.1524)
				(type default)
			)
			(layer "F.SilkS")
		)
		(fp_poly
			(pts
				(xy -2.2352 -0.298958) (xy -2.2352 -1.001014) (xy -1.533144 -0.649986)
			)
			(stroke
				(width 0)
				(type default)
			)
			(fill yes)
			(layer "F.SilkS")
		)
		(fp_line
			(start -0.674878 -1.100074)
			(end 0.674878 -1.100074)
			(stroke
				(width 0.1)
				(type default)
			)
			(layer "F.Fab")
		)
		(fp_line
			(start -0.674878 1.100074)
			(end -0.674878 -1.100074)
			(stroke
				(width 0.1)
				(type default)
			)
			(layer "F.Fab")
		)
		(fp_line
			(start 0.674878 -1.100074)
			(end 0.674878 1.100074)
			(stroke
				(width 0.1)
				(type default)
			)
			(layer "F.Fab")
		)
		(fp_line
			(start 0.674878 1.100074)
			(end -0.674878 1.100074)
			(stroke
				(width 0.1)
				(type default)
			)
			(layer "F.Fab")
		)
		(fp_poly
			(pts
				(xy -2.2352 -0.298958) (xy -2.2352 -1.001014) (xy -1.533144 -0.649986)
			)
			(stroke
				(width 0)
				(type default)
			)
			(fill yes)
			(layer "F.Fab")
		)
		(pad "1" smd rect
			(at -0.94996 -0.649986 90)
			(size 0.4318 0.508)
			(layers "F.Cu" "F.Mask" "F.Paste")
			(net "GND")
		)
		(pad "2" smd rect
			(at -0.94996 0 90)
			(size 0.4318 0.508)
			(layers "F.Cu" "F.Mask" "F.Paste")
			(net "PWRGD_P1V0_AUX_DELAY")
		)
		(pad "3" smd rect
			(at -0.94996 0.649986 90)
			(size 0.4318 0.508)
			(layers "F.Cu" "F.Mask" "F.Paste")
			(net "Net_30")
		)
		(pad "4" smd rect
			(at 0.94996 0.649986 90)
			(size 0.4318 0.508)
			(layers "F.Cu" "F.Mask" "F.Paste")
			(net "Net_32")
		)
		(pad "5" smd rect
			(at 0.94996 0 90)
			(size 0.4318 0.508)
			(layers "F.Cu" "F.Mask" "F.Paste")
			(net "Net_31")
		)
		(pad "6" smd rect
			(at 0.94996 -0.649986 90)
			(size 0.4318 0.508)
			(layers "F.Cu" "F.Mask" "F.Paste")
			(net "LED_D22_R1")
		)
	)
	(footprint ""
		(layer "F.Cu")
		(at 35.031172 -83.816952 -90)
		(property "Reference" "R657"
			(at 0 0 270)
			(layer "F.SilkS")
			(hide yes)
			(effects
				(font
					(size 1.27 1.27)
				)
			)
		)
		(property "Value" ""
			(at 0 0 270)
			(layer "F.Fab")
			(effects
				(font
					(size 1.27 1.27)
				)
			)
		)
		(duplicate_pad_numbers_are_jumpers no)
		(fp_line
			(start -0.7874 0.4064)
			(end -0.7874 -0.4064)
			(stroke
				(width 0.1524)
				(type default)
			)
			(layer "F.SilkS")
		)
		(fp_line
			(start 0.7874 0.4064)
			(end -0.7874 0.4064)
			(stroke
				(width 0.1524)
				(type default)
			)
			(layer "F.SilkS")
		)
		(fp_line
			(start -0.7874 -0.4064)
			(end 0.7874 -0.4064)
			(stroke
				(width 0.1524)
				(type default)
			)
			(layer "F.SilkS")
		)
		(fp_line
			(start 0.7874 -0.4064)
			(end 0.7874 0.4064)
			(stroke
				(width 0.1524)
				(type default)
			)
			(layer "F.SilkS")
		)
		(fp_line
			(start -0.67945 0.3048)
			(end -0.67945 -0.305054)
			(stroke
				(width 0.1)
				(type default)
			)
			(layer "F.Fab")
		)
		(fp_line
			(start -0.12065 0.3048)
			(end -0.67945 0.3048)
			(stroke
				(width 0.1)
				(type default)
			)
			(layer "F.Fab")
		)
		(fp_line
			(start 0.120396 0.3048)
			(end 0.120396 0.2794)
			(stroke
				(width 0.1)
				(type default)
			)
			(layer "F.Fab")
		)
		(fp_line
			(start 0.67945 0.3048)
			(end 0.120396 0.3048)
			(stroke
				(width 0.1)
				(type default)
			)
			(layer "F.Fab")
		)
		(fp_line
			(start -0.12065 0.2794)
			(end -0.12065 0.3048)
			(stroke
				(width 0.1)
				(type default)
			)
			(layer "F.Fab")
		)
		(fp_line
			(start 0.120396 0.2794)
			(end -0.12065 0.2794)
			(stroke
				(width 0.1)
				(type default)
			)
			(layer "F.Fab")
		)
		(fp_line
			(start -0.12065 -0.2794)
			(end 0.12065 -0.2794)
			(stroke
				(width 0.1)
				(type default)
			)
			(layer "F.Fab")
		)
		(fp_line
			(start 0.12065 -0.2794)
			(end 0.12065 -0.3048)
			(stroke
				(width 0.1)
				(type default)
			)
			(layer "F.Fab")
		)
		(fp_line
			(start 0.12065 -0.3048)
			(end 0.67945 -0.3048)
			(stroke
				(width 0.1)
				(type default)
			)
			(layer "F.Fab")
		)
		(fp_line
			(start 0.67945 -0.3048)
			(end 0.67945 0.3048)
			(stroke
				(width 0.1)
				(type default)
			)
			(layer "F.Fab")
		)
		(fp_line
			(start -0.67945 -0.305054)
			(end -0.12065 -0.305054)
			(stroke
				(width 0.1)
				(type default)
			)
			(layer "F.Fab")
		)
		(fp_line
			(start -0.12065 -0.305054)
			(end -0.12065 -0.2794)
			(stroke
				(width 0.1)
				(type default)
			)
			(layer "F.Fab")
		)
		(pad "1" smd circle
			(at -0.40005 0 270)
			(size 0 0)
			(layers "F.Cu" "F.Mask" "F.Paste")
			(net "P3V3_AUX")
		)
		(pad "2" smd circle
			(at 0.40005 0 270)
			(size 0 0)
			(layers "F.Cu" "F.Mask" "F.Paste")
			(net "EMMC_DT2_R")
		)
	)
)
